Created on vSure / Trilogy - Netlist Compare Summary.

Version 

FTP Site : valor.com
WEB Site : http://www.valor.com 

DATE :  07 Dec 2012
TIME :  19:20:34


     MISMATCH SUMMARY REPORT
     -----------------------

Job  : 12433-1m                Job  : 12433-1m
Step : pcb                     Step : pcb
Type : CAD                     Type : CURCAD

-----------------------------------------------

 Mismatch Type: shorted

   P12V                  -   NET00007            
   P12V_FAN6             -    "                  
   P12V_FAN2             -    "                  
   P12V_FAN3             -    "                  
   P12V_FAN5             -    "                  
   P3V3_IN               -    "                  
   P12V_FAN1             -    "                  
   P12V_FAN4             -    "                  
   P3V3                  -   NET00035            
   P3V3_LX_COPPER        -    "                  
   ADM1276_GATE          -   NET00241            
   ADM1276_GATE_DRV      -    "                  

 Total : 3
-----------------------------------------------

 Mismatch Type: broken


 Total : 0
-----------------------------------------------

 Mismatch Type: missing


 Total : 0
-----------------------------------------------

 Mismatch Type: extra


 Total : 0
-----------------------------------------------
